# SCM (Grand Teton) — schematic netlist excerpt (pin names and nets, part order shuffled) for the footprints in the layout excerpt that follows; sources: Cadence DE-HDL packaged netlist, KiCad conversion of 12092022_DA0F0TMDCD0_F0T_Management_Board_D_brd_V3_OCP.brd

R358  Q_RES  120 1% CHIP  pkg 0402LF  page 20 : A = M_BMC_DDR4_MA<7> ; B = P1V2_AUX
R180  Q_RES  33.2 1% CHIP  pkg 0402LF  page 13 : A = SPI_BMC_MISO_IO1_R ; B = SPI_BMC_BOOT_MISO

(kicad_pcb
	(version 20260206)
	(generator "pcbnew")
	(generator_version "10.0")
	(general
		(thickness 1.6)
		(legacy_teardrops no)
	)
	(paper "A4")
	(title_block
		(title "12092022_DA0F0TMDCD0_F0T_Management_Board_D_brd_V3_OCP.brd")
		(comment 1 "Grand Teton / footprints 976-977 of 1440")
	)
	(layers
		(0 "F.Cu" signal "TOP")
		(4 "In1.Cu" signal "GND")
		(6 "In2.Cu" signal "IN1")
		(8 "In3.Cu" signal "GND1")
		(10 "In4.Cu" signal "IN2")
		(12 "In5.Cu" signal "VCC")
		(14 "In6.Cu" signal "VCC1")
		(16 "In7.Cu" signal "IN3")
		(18 "In8.Cu" signal "GND2")
		(20 "In9.Cu" signal "IN4")
		(22 "In10.Cu" signal "GND3")
		(2 "B.Cu" signal "BOTTOM")
		(9 "F.Adhes" user "F.Adhesive")
		(11 "B.Adhes" user "B.Adhesive")
		(13 "F.Paste" user "Package Geometry/Pastemask Top")
		(15 "B.Paste" user "Package Geometry/Pastemask Bottom")
		(5 "F.SilkS" user "Ref Des/Silkscreen Top")
		(7 "B.SilkS" user "Ref Des/Silkscreen Bottom")
		(1 "F.Mask" user "Board Geometry/Soldermask Top")
		(3 "B.Mask" user "Board Geometry/Soldermask Bottom")
		(17 "Dwgs.User" user "User.Drawings")
		(19 "Cmts.User" user "User.Comments")
		(21 "Eco1.User" user "User.Eco1")
		(23 "Eco2.User" user "User.Eco2")
		(25 "Edge.Cuts" user "Board Geometry/Outline")
		(27 "Margin" user)
		(31 "F.CrtYd" user "Package Geometry/Place Bound Top")
		(29 "B.CrtYd" user "Package Geometry/Place Bound Bottom")
		(35 "F.Fab" user "Ref Des/Assembly Top")
		(33 "B.Fab" user "Ref Des/Assembly Bottom")
	)
	(footprint ""
		(layer "B.Cu")
		(at 55.8546 -66.0146 -90)
		(property "Reference" "R180"
			(at 0 0 90)
			(layer "B.SilkS")
			(hide yes)
			(effects
				(font
					(size 1.27 1.27)
				)
				(justify mirror)
			)
		)
		(property "Value" ""
			(at 0 0 90)
			(layer "B.Fab")
			(effects
				(font
					(size 1.27 1.27)
				)
				(justify mirror)
			)
		)
		(duplicate_pad_numbers_are_jumpers no)
		(fp_line
			(start -0.7874 0.4064)
			(end 0.7874 0.4064)
			(stroke
				(width 0.1524)
				(type default)
			)
			(layer "B.SilkS")
		)
		(fp_line
			(start 0.7874 0.4064)
			(end 0.7874 -0.4064)
			(stroke
				(width 0.1524)
				(type default)
			)
			(layer "B.SilkS")
		)
		(fp_line
			(start -0.7874 -0.4064)
			(end -0.7874 0.4064)
			(stroke
				(width 0.1524)
				(type default)
			)
			(layer "B.SilkS")
		)
		(fp_line
			(start 0.7874 -0.4064)
			(end -0.7874 -0.4064)
			(stroke
				(width 0.1524)
				(type default)
			)
			(layer "B.SilkS")
		)
		(fp_line
			(start -0.67945 0.3048)
			(end -0.120396 0.3048)
			(stroke
				(width 0.1)
				(type default)
			)
			(layer "B.Fab")
		)
		(fp_line
			(start -0.120396 0.3048)
			(end -0.120396 0.2794)
			(stroke
				(width 0.1)
				(type default)
			)
			(layer "B.Fab")
		)
		(fp_line
			(start 0.12065 0.3048)
			(end 0.67945 0.3048)
			(stroke
				(width 0.1)
				(type default)
			)
			(layer "B.Fab")
		)
		(fp_line
			(start 0.67945 0.3048)
			(end 0.67945 -0.305054)
			(stroke
				(width 0.1)
				(type default)
			)
			(layer "B.Fab")
		)
		(fp_line
			(start -0.120396 0.2794)
			(end 0.12065 0.2794)
			(stroke
				(width 0.1)
				(type default)
			)
			(layer "B.Fab")
		)
		(fp_line
			(start 0.12065 0.2794)
			(end 0.12065 0.3048)
			(stroke
				(width 0.1)
				(type default)
			)
			(layer "B.Fab")
		)
		(fp_line
			(start -0.12065 -0.2794)
			(end -0.12065 -0.3048)
			(stroke
				(width 0.1)
				(type default)
			)
			(layer "B.Fab")
		)
		(fp_line
			(start 0.12065 -0.2794)
			(end -0.12065 -0.2794)
			(stroke
				(width 0.1)
				(type default)
			)
			(layer "B.Fab")
		)
		(fp_line
			(start -0.67945 -0.3048)
			(end -0.67945 0.3048)
			(stroke
				(width 0.1)
				(type default)
			)
			(layer "B.Fab")
		)
		(fp_line
			(start -0.12065 -0.3048)
			(end -0.67945 -0.3048)
			(stroke
				(width 0.1)
				(type default)
			)
			(layer "B.Fab")
		)
		(fp_line
			(start 0.12065 -0.305054)
			(end 0.12065 -0.2794)
			(stroke
				(width 0.1)
				(type default)
			)
			(layer "B.Fab")
		)
		(fp_line
			(start 0.67945 -0.305054)
			(end 0.12065 -0.305054)
			(stroke
				(width 0.1)
				(type default)
			)
			(layer "B.Fab")
		)
		(pad "1" smd circle
			(at 0.40005 0 90)
			(size 0 0)
			(layers "B.Cu" "B.Mask" "B.Paste")
			(net "SPI_BMC_MISO_IO1_R")
		)
		(pad "2" smd circle
			(at -0.40005 0 90)
			(size 0 0)
			(layers "B.Cu" "B.Mask" "B.Paste")
			(net "SPI_BMC_BOOT_MISO")
		)
	)
	(footprint ""
		(layer "B.Cu")
		(at 85.281262 -44.427394 180)
		(property "Reference" "R358"
			(at 0 0 0)
			(layer "B.SilkS")
			(hide yes)
			(effects
				(font
					(size 1.27 1.27)
				)
				(justify mirror)
			)
		)
		(property "Value" ""
			(at 0 0 0)
			(layer "B.Fab")
			(effects
				(font
					(size 1.27 1.27)
				)
				(justify mirror)
			)
		)
		(duplicate_pad_numbers_are_jumpers no)
		(fp_line
			(start 0.7874 0.4064)
			(end 0.7874 -0.4064)
			(stroke
				(width 0.1524)
				(type default)
			)
			(layer "B.SilkS")
		)
		(fp_line
			(start 0.7874 -0.4064)
			(end -0.7874 -0.4064)
			(stroke
				(width 0.1524)
				(type default)
			)
			(layer "B.SilkS")
		)
		(fp_line
			(start -0.7874 0.4064)
			(end 0.7874 0.4064)
			(stroke
				(width 0.1524)
				(type default)
			)
			(layer "B.SilkS")
		)
		(fp_line
			(start -0.7874 -0.4064)
			(end -0.7874 0.4064)
			(stroke
				(width 0.1524)
				(type default)
			)
			(layer "B.SilkS")
		)
		(fp_line
			(start 0.67945 0.3048)
			(end 0.67945 -0.305054)
			(stroke
				(width 0.1)
				(type default)
			)
			(layer "B.Fab")
		)
		(fp_line
			(start 0.67945 -0.305054)
			(end 0.12065 -0.305054)
			(stroke
				(width 0.1)
				(type default)
			)
			(layer "B.Fab")
		)
		(fp_line
			(start 0.12065 0.3048)
			(end 0.67945 0.3048)
			(stroke
				(width 0.1)
				(type default)
			)
			(layer "B.Fab")
		)
		(fp_line
			(start 0.12065 0.2794)
			(end 0.12065 0.3048)
			(stroke
				(width 0.1)
				(type default)
			)
			(layer "B.Fab")
		)
		(fp_line
			(start 0.12065 -0.2794)
			(end -0.12065 -0.2794)
			(stroke
				(width 0.1)
				(type default)
			)
			(layer "B.Fab")
		)
		(fp_line
			(start 0.12065 -0.305054)
			(end 0.12065 -0.2794)
			(stroke
				(width 0.1)
				(type default)
			)
			(layer "B.Fab")
		)
		(fp_line
			(start -0.120396 0.3048)
			(end -0.120396 0.2794)
			(stroke
				(width 0.1)
				(type default)
			)
			(layer "B.Fab")
		)
		(fp_line
			(start -0.120396 0.2794)
			(end 0.12065 0.2794)
			(stroke
				(width 0.1)
				(type default)
			)
			(layer "B.Fab")
		)
		(fp_line
			(start -0.12065 -0.2794)
			(end -0.12065 -0.3048)
			(stroke
				(width 0.1)
				(type default)
			)
			(layer "B.Fab")
		)
		(fp_line
			(start -0.12065 -0.3048)
			(end -0.67945 -0.3048)
			(stroke
				(width 0.1)
				(type default)
			)
			(layer "B.Fab")
		)
		(fp_line
			(start -0.67945 0.3048)
			(end -0.120396 0.3048)
			(stroke
				(width 0.1)
				(type default)
			)
			(layer "B.Fab")
		)
		(fp_line
			(start -0.67945 -0.3048)
			(end -0.67945 0.3048)
			(stroke
				(width 0.1)
				(type default)
			)
			(layer "B.Fab")
		)
		(pad "1" smd circle
			(at 0.40005 0)
			(size 0 0)
			(layers "B.Cu" "B.Mask" "B.Paste")
			(net "M_BMC_DDR4_MA<7>")
		)
		(pad "2" smd circle
			(at -0.40005 0)
			(size 0 0)
			(layers "B.Cu" "B.Mask" "B.Paste")
			(net "P1V2_AUX")
		)
	)
)
